(kicad_pcb
	(version 20260206)
	(generator "pcbnew")
	(generator_version "10.0")
	(general
		(thickness 1.6)
		(legacy_teardrops no)
	)
	(paper "A4")
	(title_block
		(title "Bryce Canyon_F.DPB_16315-1-OCP.brd")
		(comment 1 "Bryce Canyon / footprints 127-134 of 2223")
	)
	(layers
		(0 "F.Cu" signal "TOP")
		(4 "In1.Cu" signal "L2GND")
		(6 "In2.Cu" signal "L3")
		(8 "In3.Cu" signal "L4GND")
		(10 "In4.Cu" signal "L5")
		(12 "In5.Cu" signal "L6VCC")
		(14 "In6.Cu" signal "L7VCC")
		(16 "In7.Cu" signal "L8")
		(18 "In8.Cu" signal "L9GND")
		(20 "In9.Cu" signal "L10")
		(22 "In10.Cu" signal "L11GND")
		(2 "B.Cu" signal "BOTTOM")
		(9 "F.Adhes" user "F.Adhesive")
		(11 "B.Adhes" user "B.Adhesive")
		(13 "F.Paste" user "Package Geometry/Pastemask Top")
		(15 "B.Paste" user "Package Geometry/Pastemask Bottom")
		(5 "F.SilkS" user "Ref Des/Silkscreen Top")
		(7 "B.SilkS" user "Ref Des/Silkscreen Bottom")
		(1 "F.Mask" user "Board Geometry/Soldermask Top")
		(3 "B.Mask" user "Board Geometry/Soldermask Bottom")
		(17 "Dwgs.User" user "User.Drawings")
		(19 "Cmts.User" user "User.Comments")
		(21 "Eco1.User" user "User.Eco1")
		(23 "Eco2.User" user "User.Eco2")
		(25 "Edge.Cuts" user "Board Geometry/Outline")
		(27 "Margin" user)
		(31 "F.CrtYd" user "Package Geometry/Place Bound Top")
		(29 "B.CrtYd" user "Package Geometry/Place Bound Bottom")
		(35 "F.Fab" user "Ref Des/Assembly Top")
		(33 "B.Fab" user "Ref Des/Assembly Bottom")
	)
	(footprint ""
		(layer "F.Cu")
		(at 267.87475 11.5443 180)
		(property "Reference" "C49"
			(at 0 0 180)
			(layer "F.SilkS")
			(hide yes)
			(effects
				(font
					(size 1.27 1.27)
				)
			)
		)
		(property "Value" "SCD1U16V2KX-3GP"
			(at 1.1811 -2.7051 180)
			(unlocked yes)
			(layer "F.Fab")
			(hide yes)
			(effects
				(font
					(size 1.016 1.016)
					(thickness 0.1524)
				)
			)
		)
		(property "Device Type" "C402H22"
			(at 1.1811 -4.2291 180)
			(unlocked yes)
			(layer "F.Fab")
			(hide yes)
			(effects
				(font
					(size 1.016 1.016)
					(thickness 0.1524)
				)
			)
		)
		(duplicate_pad_numbers_are_jumpers no)
		(fp_rect
			(start -0.4318 0.9525)
			(end 0.4318 -0.9525)
			(stroke
				(width 0)
				(type default)
			)
			(fill no)
			(layer "F.CrtYd")
		)
		(fp_rect
			(start -0.4318 0.9525)
			(end 0.4318 -0.9525)
			(stroke
				(width 0)
				(type default)
			)
			(fill no)
			(layer "F.Fab")
		)
		(pad "1" smd custom
			(at 0 -0.4445 180)
			(size 0.1524 0.1524)
			(layers "F.Cu" "F.Mask" "F.Paste")
			(net "P5V_B")
			(options
				(clearance outline)
				(anchor circle)
			)
			(primitives
				(gr_poly
					(pts
						(arc
							(start 0.3048 -0.2032)
							(mid 0.275042 -0.275042)
							(end 0.2032 -0.3048)
						)
						(arc
							(start -0.2032 -0.3048)
							(mid -0.275042 -0.275042)
							(end -0.3048 -0.2032)
						)
						(arc
							(start -0.3048 0.2032)
							(mid -0.275042 0.275042)
							(end -0.2032 0.3048)
						)
						(arc
							(start 0.2032 0.3048)
							(mid 0.275042 0.275042)
							(end 0.3048 0.2032)
						)
					)
					(width 0)
					(fill yes)
				)
			)
		)
		(pad "2" smd custom
			(at 0 0.4445 180)
			(size 0.1524 0.1524)
			(layers "F.Cu" "F.Mask" "F.Paste")
			(net "GND")
			(options
				(clearance outline)
				(anchor circle)
			)
			(primitives
				(gr_poly
					(pts
						(arc
							(start 0.3048 -0.2032)
							(mid 0.275042 -0.275042)
							(end 0.2032 -0.3048)
						)
						(arc
							(start -0.2032 -0.3048)
							(mid -0.275042 -0.275042)
							(end -0.3048 -0.2032)
						)
						(arc
							(start -0.3048 0.2032)
							(mid -0.275042 0.275042)
							(end -0.2032 0.3048)
						)
						(arc
							(start 0.2032 0.3048)
							(mid 0.275042 0.275042)
							(end 0.3048 0.2032)
						)
					)
					(width 0)
					(fill yes)
				)
			)
		)
	)
	(footprint ""
		(layer "F.Cu")
		(at 272.542 -330.704952 180)
		(property "Reference" "VIA53"
			(at 0 0 180)
			(layer "F.SilkS")
			(hide yes)
			(effects
				(font
					(size 1.27 1.27)
				)
			)
		)
		(property "Value" "100OHM-8L-1D6MM-L18L16-GP"
			(at -3.7211 -4.5085 180)
			(unlocked yes)
			(layer "F.Fab")
			(hide yes)
			(effects
				(font
					(size 1.016 1.016)
					(thickness 0.1524)
				)
			)
		)
		(property "Device Type" "VIA-PCIE-4P-394076"
			(at -3.7211 -6.0325 180)
			(unlocked yes)
			(layer "F.Fab")
			(hide yes)
			(effects
				(font
					(size 1.016 1.016)
					(thickness 0.1524)
				)
			)
		)
		(duplicate_pad_numbers_are_jumpers no)
		(fp_rect
			(start -1.9685 0.381)
			(end 1.9685 -0.381)
			(stroke
				(width 0)
				(type default)
			)
			(fill no)
			(layer "F.CrtYd")
		)
		(fp_rect
			(start -1.9685 0.381)
			(end 1.9685 -0.381)
			(stroke
				(width 0)
				(type default)
			)
			(fill no)
			(layer "F.Fab")
		)
		(pad "1" thru_hole circle
			(at -1.5875 0 180)
			(size 0.508 0.508)
			(drill 0.254)
			(layers "*.Cu" "*.Mask")
			(remove_unused_layers no)
			(net "GND")
			(clearance 0.127)
			(thermal_gap 0.127)
		)
		(pad "2" thru_hole circle
			(at -0.5715 0 180)
			(size 0.508 0.508)
			(drill 0.254)
			(layers "*.Cu" "*.Mask")
			(remove_unused_layers no)
			(net "PHY_SCC_A_TO_DRV_A_16_DP")
			(clearance 0.127)
			(thermal_gap 0.127)
		)
		(pad "3" thru_hole circle
			(at 0.5715 0 180)
			(size 0.508 0.508)
			(drill 0.254)
			(layers "*.Cu" "*.Mask")
			(remove_unused_layers no)
			(net "PHY_SCC_A_TO_DRV_A_16_DN")
			(clearance 0.127)
			(thermal_gap 0.127)
		)
		(pad "4" thru_hole circle
			(at 1.5875 0 180)
			(size 0.508 0.508)
			(drill 0.254)
			(layers "*.Cu" "*.Mask")
			(remove_unused_layers no)
			(net "GND")
			(clearance 0.127)
			(thermal_gap 0.127)
		)
	)
	(footprint ""
		(layer "F.Cu")
		(at 169.200068 -27.487626)
		(property "Reference" "R389"
			(at 0 0 0)
			(layer "F.SilkS")
			(hide yes)
			(effects
				(font
					(size 1.27 1.27)
				)
			)
		)
		(property "Value" "10KR2F-2-GP"
			(at 0.064008 -3.993896 0)
			(unlocked yes)
			(layer "F.Fab")
			(hide yes)
			(effects
				(font
					(size 1.016 1.016)
					(thickness 0.1524)
				)
			)
		)
		(property "Device Type" "R402H16"
			(at 0.064008 -5.517896 0)
			(unlocked yes)
			(layer "F.Fab")
			(hide yes)
			(effects
				(font
					(size 1.016 1.016)
					(thickness 0.1524)
				)
			)
		)
		(duplicate_pad_numbers_are_jumpers no)
		(fp_line
			(start -0.508 -0.9398)
			(end -0.508 0.9398)
			(stroke
				(width 0.1524)
				(type default)
			)
			(layer "F.SilkS")
		)
		(fp_line
			(start 0.508 -0.9398)
			(end -0.508 -0.9398)
			(stroke
				(width 0.1524)
				(type default)
			)
			(layer "F.SilkS")
		)
		(fp_rect
			(start -0.508 0.9398)
			(end 0.508 -0.9398)
			(stroke
				(width 0)
				(type default)
			)
			(fill no)
			(layer "F.CrtYd")
		)
		(fp_rect
			(start -0.508 0.9398)
			(end 0.508 -0.9398)
			(stroke
				(width 0)
				(type default)
			)
			(fill no)
			(layer "F.Fab")
		)
		(pad "1" smd custom
			(at 0 -0.4445)
			(size 0.1397 0.1397)
			(layers "F.Cu" "F.Mask" "F.Paste")
			(net "SYS_A_RESET_N")
			(options
				(clearance outline)
				(anchor circle)
			)
			(primitives
				(gr_poly
					(pts
						(arc
							(start -0.1778 -0.2794)
							(mid -0.249642 -0.249642)
							(end -0.2794 -0.1778)
						)
						(arc
							(start -0.2794 0.1778)
							(mid -0.249642 0.249642)
							(end -0.1778 0.2794)
						)
						(arc
							(start 0.1778 0.2794)
							(mid 0.249642 0.249642)
							(end 0.2794 0.1778)
						)
						(arc
							(start 0.2794 -0.1778)
							(mid 0.249642 -0.249642)
							(end 0.1778 -0.2794)
						)
					)
					(width 0)
					(fill yes)
				)
			)
		)
		(pad "2" smd custom
			(at 0 0.4445)
			(size 0.1397 0.1397)
			(layers "F.Cu" "F.Mask" "F.Paste")
			(net "GND")
			(options
				(clearance outline)
				(anchor circle)
			)
			(primitives
				(gr_poly
					(pts
						(arc
							(start -0.1778 -0.2794)
							(mid -0.249642 -0.249642)
							(end -0.2794 -0.1778)
						)
						(arc
							(start -0.2794 0.1778)
							(mid -0.249642 0.249642)
							(end -0.1778 0.2794)
						)
						(arc
							(start 0.1778 0.2794)
							(mid 0.249642 0.249642)
							(end 0.2794 0.1778)
						)
						(arc
							(start 0.2794 -0.1778)
							(mid 0.249642 -0.249642)
							(end 0.1778 -0.2794)
						)
					)
					(width 0)
					(fill yes)
				)
			)
		)
	)
	(footprint ""
		(layer "F.Cu")
		(at 363.7788 -138.3284 90)
		(property "Reference" "C557"
			(at 0 0 90)
			(layer "F.SilkS")
			(hide yes)
			(effects
				(font
					(size 1.27 1.27)
				)
			)
		)
		(property "Value" "SC1U25V3KX-GP"
			(at 0 -2.8194 90)
			(unlocked yes)
			(layer "F.Fab")
			(hide yes)
			(effects
				(font
					(size 1.016 1.016)
					(thickness 0.1524)
				)
			)
		)
		(property "Device Type" "C603H36"
			(at 0 -4.3434 90)
			(unlocked yes)
			(layer "F.Fab")
			(hide yes)
			(effects
				(font
					(size 1.016 1.016)
					(thickness 0.1524)
				)
			)
		)
		(duplicate_pad_numbers_are_jumpers no)
		(fp_line
			(start 0.508 0)
			(end -0.508 0)
			(stroke
				(width 0.2032)
				(type default)
			)
			(layer "F.SilkS")
		)
		(fp_rect
			(start -0.5842 1.3335)
			(end 0.5842 -1.3335)
			(stroke
				(width 0)
				(type default)
			)
			(fill no)
			(layer "F.CrtYd")
		)
		(fp_rect
			(start -0.5842 1.3335)
			(end 0.5842 -1.3335)
			(stroke
				(width 0)
				(type default)
			)
			(fill no)
			(layer "F.Fab")
		)
		(pad "1" smd custom
			(at 0 -0.762 90)
			(size 0.2159 0.2159)
			(layers "F.Cu" "F.Mask" "F.Paste")
			(net "AGND_CURRENT_MONOB")
			(options
				(clearance outline)
				(anchor circle)
			)
			(primitives
				(gr_poly
					(pts
						(arc
							(start -0.3302 -0.4318)
							(mid -0.402042 -0.402042)
							(end -0.4318 -0.3302)
						)
						(arc
							(start -0.4318 0.3302)
							(mid -0.402042 0.402042)
							(end -0.3302 0.4318)
						)
						(arc
							(start 0.3302 0.4318)
							(mid 0.402042 0.402042)
							(end 0.4318 0.3302)
						)
						(arc
							(start 0.4318 -0.3302)
							(mid 0.402042 -0.402042)
							(end 0.3302 -0.4318)
						)
					)
					(width 0)
					(fill yes)
				)
			)
		)
		(pad "2" smd custom
			(at 0 0.762 90)
			(size 0.2159 0.2159)
			(layers "F.Cu" "F.Mask" "F.Paste")
			(net "MB1_P12V_HS")
			(options
				(clearance outline)
				(anchor circle)
			)
			(primitives
				(gr_poly
					(pts
						(arc
							(start -0.3302 -0.4318)
							(mid -0.402042 -0.402042)
							(end -0.4318 -0.3302)
						)
						(arc
							(start -0.4318 0.3302)
							(mid -0.402042 0.402042)
							(end -0.3302 0.4318)
						)
						(arc
							(start 0.3302 0.4318)
							(mid 0.402042 0.402042)
							(end 0.4318 0.3302)
						)
						(arc
							(start 0.4318 -0.3302)
							(mid 0.402042 -0.402042)
							(end 0.3302 -0.4318)
						)
					)
					(width 0)
					(fill yes)
				)
			)
		)
	)
	(footprint ""
		(layer "F.Cu")
		(at 394.56995 -291.127942 -90)
		(property "Reference" "R313"
			(at 0 0 270)
			(layer "F.SilkS")
			(hide yes)
			(effects
				(font
					(size 1.27 1.27)
				)
			)
		)
		(property "Value" "2R6F-GP"
			(at -0.0508 -4.8514 270)
			(unlocked yes)
			(layer "F.Fab")
			(hide yes)
			(effects
				(font
					(size 1.016 1.016)
					(thickness 0.1524)
				)
			)
		)
		(property "Device Type" "R1206H26"
			(at 0 -6.3754 270)
			(unlocked yes)
			(layer "F.Fab")
			(hide yes)
			(effects
				(font
					(size 1.016 1.016)
					(thickness 0.1524)
				)
			)
		)
		(duplicate_pad_numbers_are_jumpers no)
		(fp_line
			(start -1.016 2.2352)
			(end -1.016 -2.2352)
			(stroke
				(width 0.1524)
				(type default)
			)
			(layer "F.SilkS")
		)
		(fp_line
			(start 1.016 2.2352)
			(end -1.016 2.2352)
			(stroke
				(width 0.1524)
				(type default)
			)
			(layer "F.SilkS")
		)
		(fp_line
			(start -1.016 -2.2352)
			(end 1.016 -2.2352)
			(stroke
				(width 0.1524)
				(type default)
			)
			(layer "F.SilkS")
		)
		(fp_line
			(start 1.016 -2.2352)
			(end 1.016 2.2352)
			(stroke
				(width 0.1524)
				(type default)
			)
			(layer "F.SilkS")
		)
		(fp_rect
			(start -1.0922 2.3114)
			(end 1.0922 -2.3114)
			(stroke
				(width 0)
				(type default)
			)
			(fill no)
			(layer "F.CrtYd")
		)
		(fp_poly
			(pts
				(xy -1.0922 -2.3114) (xy 1.0922 -2.3114) (xy 1.0922 2.3114) (xy -1.0922 2.3114)
			)
			(stroke
				(width 0)
				(type default)
			)
			(fill no)
			(layer "F.Fab")
		)
		(pad "1" smd rect
			(at 0 -1.397 270)
			(size 1.651 1.27)
			(layers "F.Cu" "F.Mask" "F.Paste")
			(net "P5V_HDD8")
		)
		(pad "2" smd rect
			(at 0 1.397 270)
			(size 1.651 1.27)
			(layers "F.Cu" "F.Mask" "F.Paste")
			(net "5V_PRE_8")
		)
	)
	(footprint ""
		(layer "F.Cu")
		(at 127.113284 -158.660592 90)
		(property "Reference" "C234"
			(at 0 0 90)
			(layer "F.SilkS")
			(hide yes)
			(effects
				(font
					(size 1.27 1.27)
				)
			)
		)
		(property "Value" "SCD01U16V1KX-GP"
			(at -2.8321 -1.7399 90)
			(unlocked yes)
			(layer "F.Fab")
			(hide yes)
			(effects
				(font
					(size 1.016 1.016)
					(thickness 0.1524)
				)
			)
		)
		(property "Device Type" "C0201H13"
			(at -2.8321 -3.2639 90)
			(unlocked yes)
			(layer "F.Fab")
			(hide yes)
			(effects
				(font
					(size 1.016 1.016)
					(thickness 0.1524)
				)
			)
		)
		(duplicate_pad_numbers_are_jumpers no)
		(fp_rect
			(start -0.2794 0.6477)
			(end 0.2794 -0.6477)
			(stroke
				(width 0)
				(type default)
			)
			(fill no)
			(layer "F.CrtYd")
		)
		(fp_rect
			(start -0.2794 0.6477)
			(end 0.2794 -0.6477)
			(stroke
				(width 0)
				(type default)
			)
			(fill no)
			(layer "F.Fab")
		)
		(pad "1" smd custom
			(at 0 -0.2794 90)
			(size 0.0762 0.0762)
			(layers "F.Cu" "F.Mask" "F.Paste")
			(net "SAS_HDD_RX_P15")
			(options
				(clearance outline)
				(anchor circle)
			)
			(primitives
				(gr_poly
					(pts
						(arc
							(start 0.1524 -0.127)
							(mid 0.137521 -0.162921)
							(end 0.1016 -0.1778)
						)
						(arc
							(start -0.1016 -0.1778)
							(mid -0.137521 -0.162921)
							(end -0.1524 -0.127)
						)
						(arc
							(start -0.1524 0.127)
							(mid -0.137521 0.162921)
							(end -0.1016 0.1778)
						)
						(arc
							(start 0.1016 0.1778)
							(mid 0.137521 0.162921)
							(end 0.1524 0.127)
						)
					)
					(width 0)
					(fill yes)
				)
			)
		)
		(pad "2" smd custom
			(at 0 0.2794 90)
			(size 0.0762 0.0762)
			(layers "F.Cu" "F.Mask" "F.Paste")
			(net "PHY_SCC_A_TO_DRV_A_15_DP")
			(options
				(clearance outline)
				(anchor circle)
			)
			(primitives
				(gr_poly
					(pts
						(arc
							(start 0.1524 -0.127)
							(mid 0.137521 -0.162921)
							(end 0.1016 -0.1778)
						)
						(arc
							(start -0.1016 -0.1778)
							(mid -0.137521 -0.162921)
							(end -0.1524 -0.127)
						)
						(arc
							(start -0.1524 0.127)
							(mid -0.137521 0.162921)
							(end -0.1016 0.1778)
						)
						(arc
							(start 0.1016 0.1778)
							(mid 0.137521 0.162921)
							(end 0.1524 0.127)
						)
					)
					(width 0)
					(fill yes)
				)
			)
		)
	)
	(footprint ""
		(layer "F.Cu")
		(at 222.6056 -115.5446 -90)
		(property "Reference" "R181"
			(at 0 0 270)
			(layer "F.SilkS")
			(hide yes)
			(effects
				(font
					(size 1.27 1.27)
				)
			)
		)
		(property "Value" "0R2J-2-GP"
			(at 0.064008 -3.993896 270)
			(unlocked yes)
			(layer "F.Fab")
			(hide yes)
			(effects
				(font
					(size 1.016 1.016)
					(thickness 0.1524)
				)
			)
		)
		(property "Device Type" "R402H16"
			(at 0.064008 -5.517896 270)
			(unlocked yes)
			(layer "F.Fab")
			(hide yes)
			(effects
				(font
					(size 1.016 1.016)
					(thickness 0.1524)
				)
			)
		)
		(duplicate_pad_numbers_are_jumpers no)
		(fp_line
			(start -0.508 -0.9398)
			(end -0.508 0.9398)
			(stroke
				(width 0.1524)
				(type default)
			)
			(layer "F.SilkS")
		)
		(fp_line
			(start 0.508 -0.9398)
			(end -0.508 -0.9398)
			(stroke
				(width 0.1524)
				(type default)
			)
			(layer "F.SilkS")
		)
		(fp_rect
			(start -0.508 0.9398)
			(end 0.508 -0.9398)
			(stroke
				(width 0)
				(type default)
			)
			(fill no)
			(layer "F.CrtYd")
		)
		(fp_rect
			(start -0.508 0.9398)
			(end 0.508 -0.9398)
			(stroke
				(width 0)
				(type default)
			)
			(fill no)
			(layer "F.Fab")
		)
		(pad "1" smd custom
			(at 0 -0.4445 270)
			(size 0.1397 0.1397)
			(layers "F.Cu" "F.Mask" "F.Paste")
			(net "SLOT3_SVR_ID0_GPIO2")
			(options
				(clearance outline)
				(anchor circle)
			)
			(primitives
				(gr_poly
					(pts
						(arc
							(start -0.1778 -0.2794)
							(mid -0.249642 -0.249642)
							(end -0.2794 -0.1778)
						)
						(arc
							(start -0.2794 0.1778)
							(mid -0.249642 0.249642)
							(end -0.1778 0.2794)
						)
						(arc
							(start 0.1778 0.2794)
							(mid 0.249642 0.249642)
							(end 0.2794 0.1778)
						)
						(arc
							(start 0.2794 -0.1778)
							(mid 0.249642 -0.249642)
							(end 0.1778 -0.2794)
						)
					)
					(width 0)
					(fill yes)
				)
			)
		)
		(pad "2" smd custom
			(at 0 0.4445 270)
			(size 0.1397 0.1397)
			(layers "F.Cu" "F.Mask" "F.Paste")
			(net "COMP_A_EXP_A_SPARE_0")
			(options
				(clearance outline)
				(anchor circle)
			)
			(primitives
				(gr_poly
					(pts
						(arc
							(start -0.1778 -0.2794)
							(mid -0.249642 -0.249642)
							(end -0.2794 -0.1778)
						)
						(arc
							(start -0.2794 0.1778)
							(mid -0.249642 0.249642)
							(end -0.1778 0.2794)
						)
						(arc
							(start 0.1778 0.2794)
							(mid 0.249642 0.249642)
							(end 0.2794 0.1778)
						)
						(arc
							(start 0.2794 -0.1778)
							(mid 0.249642 -0.249642)
							(end 0.1778 -0.2794)
						)
					)
					(width 0)
					(fill yes)
				)
			)
		)
	)
	(footprint ""
		(layer "F.Cu")
		(at 111.473996 -52.085494 90)
		(property "Reference" "R758"
			(at 0 0 90)
			(layer "F.SilkS")
			(hide yes)
			(effects
				(font
					(size 1.27 1.27)
				)
			)
		)
		(property "Value" "4K7R2J-2-GP"
			(at 0.064008 -3.993896 90)
			(unlocked yes)
			(layer "F.Fab")
			(hide yes)
			(effects
				(font
					(size 1.016 1.016)
					(thickness 0.1524)
				)
			)
		)
		(property "Device Type" "R402H16"
			(at 0.064008 -5.517896 90)
			(unlocked yes)
			(layer "F.Fab")
			(hide yes)
			(effects
				(font
					(size 1.016 1.016)
					(thickness 0.1524)
				)
			)
		)
		(duplicate_pad_numbers_are_jumpers no)
		(fp_line
			(start 0.508 -0.9398)
			(end -0.508 -0.9398)
			(stroke
				(width 0.1524)
				(type default)
			)
			(layer "F.SilkS")
		)
		(fp_line
			(start -0.508 -0.9398)
			(end -0.508 0.9398)
			(stroke
				(width 0.1524)
				(type default)
			)
			(layer "F.SilkS")
		)
		(fp_rect
			(start -0.508 0.9398)
			(end 0.508 -0.9398)
			(stroke
				(width 0)
				(type default)
			)
			(fill no)
			(layer "F.CrtYd")
		)
		(fp_rect
			(start -0.508 0.9398)
			(end 0.508 -0.9398)
			(stroke
				(width 0)
				(type default)
			)
			(fill no)
			(layer "F.Fab")
		)
		(pad "1" smd custom
			(at 0 -0.4445 90)
			(size 0.1397 0.1397)
			(layers "F.Cu" "F.Mask" "F.Paste")
			(net "P12V_A")
			(options
				(clearance outline)
				(anchor circle)
			)
			(primitives
				(gr_poly
					(pts
						(arc
							(start -0.1778 -0.2794)
							(mid -0.249642 -0.249642)
							(end -0.2794 -0.1778)
						)
						(arc
							(start -0.2794 0.1778)
							(mid -0.249642 0.249642)
							(end -0.1778 0.2794)
						)
						(arc
							(start 0.1778 0.2794)
							(mid 0.249642 0.249642)
							(end 0.2794 0.1778)
						)
						(arc
							(start 0.2794 -0.1778)
							(mid 0.249642 -0.249642)
							(end 0.1778 -0.2794)
						)
					)
					(width 0)
					(fill yes)
				)
			)
		)
		(pad "2" smd custom
			(at 0 0.4445 90)
			(size 0.1397 0.1397)
			(layers "F.Cu" "F.Mask" "F.Paste")
			(net "SW_HDD_P27")
			(options
				(clearance outline)
				(anchor circle)
			)
			(primitives
				(gr_poly
					(pts
						(arc
							(start -0.1778 -0.2794)
							(mid -0.249642 -0.249642)
							(end -0.2794 -0.1778)
						)
						(arc
							(start -0.2794 0.1778)
							(mid -0.249642 0.249642)
							(end -0.1778 0.2794)
						)
						(arc
							(start 0.1778 0.2794)
							(mid 0.249642 0.249642)
							(end 0.2794 0.1778)
						)
						(arc
							(start 0.2794 -0.1778)
							(mid 0.249642 -0.249642)
							(end 0.1778 -0.2794)
						)
					)
					(width 0)
					(fill yes)
				)
			)
		)
	)
)
